# T6G (Grand Teton) — schematic netlist excerpt (pin names and nets, part order shuffled) for the footprints in the layout excerpt that follows; sources: Cadence DE-HDL packaged netlist, KiCad conversion of 04192023_DAF0TMB3IC0_F0TG_MB_C_brd_V02_OCP.brd

PC307  Q_CAP  2.2UF 10V 10% X6S  pkg C0402  page 213 : A = PVDDCR_CPU0_P1_VCC5 ; B = GND
C1352  Q_CAP  0.1UF 25V 10% X7R  pkg 0402  page 164 : A = PVDD18_S5_P0 ; B = GND

(kicad_pcb
	(version 20260206)
	(generator "pcbnew")
	(generator_version "10.0")
	(general
		(thickness 1.6)
		(legacy_teardrops no)
	)
	(paper "A4")
	(title_block
		(title "04192023_DAF0TMB3IC0_F0TG_MB_C_brd_V02_OCP.brd")
		(comment 1 "Grand Teton / footprints 1225-1226 of 8354")
	)
	(layers
		(0 "F.Cu" signal "TOP")
		(4 "In1.Cu" signal "GND")
		(6 "In2.Cu" signal "IN1")
		(8 "In3.Cu" signal "GND1")
		(10 "In4.Cu" signal "IN2")
		(12 "In5.Cu" signal "GND2")
		(14 "In6.Cu" signal "IN3")
		(16 "In7.Cu" signal "GND3")
		(18 "In8.Cu" signal "VCC")
		(20 "In9.Cu" signal "VCC1")
		(22 "In10.Cu" signal "GND4")
		(24 "In11.Cu" signal "IN4")
		(26 "In12.Cu" signal "GND5")
		(28 "In13.Cu" signal "IN5")
		(30 "In14.Cu" signal "GND6")
		(32 "In15.Cu" signal "IN6")
		(34 "In16.Cu" signal "GND7")
		(2 "B.Cu" signal "BOTTOM")
		(9 "F.Adhes" user "F.Adhesive")
		(11 "B.Adhes" user "B.Adhesive")
		(13 "F.Paste" user "Package Geometry/Pastemask Top")
		(15 "B.Paste" user "Package Geometry/Pastemask Bottom")
		(5 "F.SilkS" user "Ref Des/Silkscreen Top")
		(7 "B.SilkS" user "Ref Des/Silkscreen Bottom")
		(1 "F.Mask" user "Board Geometry/Soldermask Top")
		(3 "B.Mask" user "Board Geometry/Soldermask Bottom")
		(17 "Dwgs.User" user "User.Drawings")
		(19 "Cmts.User" user "User.Comments")
		(21 "Eco1.User" user "User.Eco1")
		(23 "Eco2.User" user "User.Eco2")
		(25 "Edge.Cuts" user "Board Geometry/Outline")
		(27 "Margin" user)
		(31 "F.CrtYd" user "Package Geometry/Place Bound Top")
		(29 "B.CrtYd" user "Package Geometry/Place Bound Bottom")
		(35 "F.Fab" user "Ref Des/Assembly Top")
		(33 "B.Fab" user "Ref Des/Assembly Bottom")
	)
	(footprint ""
		(layer "F.Cu")
		(at 77.64399 -174.960534 -90)
		(property "Reference" "PC307"
			(at 0 0 270)
			(layer "F.SilkS")
			(hide yes)
			(effects
				(font
					(size 1.27 1.27)
				)
			)
		)
		(property "Value" ""
			(at 0 0 270)
			(layer "F.Fab")
			(effects
				(font
					(size 1.27 1.27)
				)
			)
		)
		(duplicate_pad_numbers_are_jumpers no)
		(fp_line
			(start -0.7874 0.4064)
			(end -0.7874 -0.4064)
			(stroke
				(width 0.1524)
				(type default)
			)
			(layer "F.SilkS")
		)
		(fp_line
			(start -0.324866 0.4064)
			(end -0.7874 0.4064)
			(stroke
				(width 0.1524)
				(type default)
			)
			(layer "F.SilkS")
		)
		(fp_line
			(start 0.7874 0.4064)
			(end 0.411734 0.4064)
			(stroke
				(width 0.1524)
				(type default)
			)
			(layer "F.SilkS")
		)
		(fp_line
			(start -0.7874 -0.4064)
			(end 0.7874 -0.4064)
			(stroke
				(width 0.1524)
				(type default)
			)
			(layer "F.SilkS")
		)
		(fp_line
			(start 0.7874 -0.4064)
			(end 0.7874 0.4064)
			(stroke
				(width 0.1524)
				(type default)
			)
			(layer "F.SilkS")
		)
		(fp_line
			(start -0.67945 0.3048)
			(end -0.67945 -0.305054)
			(stroke
				(width 0.1)
				(type default)
			)
			(layer "F.Fab")
		)
		(fp_line
			(start -0.12065 0.3048)
			(end -0.67945 0.3048)
			(stroke
				(width 0.1)
				(type default)
			)
			(layer "F.Fab")
		)
		(fp_line
			(start 0.120396 0.3048)
			(end 0.120396 0.2794)
			(stroke
				(width 0.1)
				(type default)
			)
			(layer "F.Fab")
		)
		(fp_line
			(start 0.67945 0.3048)
			(end 0.120396 0.3048)
			(stroke
				(width 0.1)
				(type default)
			)
			(layer "F.Fab")
		)
		(fp_line
			(start -0.12065 0.2794)
			(end -0.12065 0.3048)
			(stroke
				(width 0.1)
				(type default)
			)
			(layer "F.Fab")
		)
		(fp_line
			(start 0.120396 0.2794)
			(end -0.12065 0.2794)
			(stroke
				(width 0.1)
				(type default)
			)
			(layer "F.Fab")
		)
		(fp_line
			(start -0.12065 -0.2794)
			(end 0.12065 -0.2794)
			(stroke
				(width 0.1)
				(type default)
			)
			(layer "F.Fab")
		)
		(fp_line
			(start 0.12065 -0.2794)
			(end 0.12065 -0.3048)
			(stroke
				(width 0.1)
				(type default)
			)
			(layer "F.Fab")
		)
		(fp_line
			(start 0.12065 -0.3048)
			(end 0.67945 -0.3048)
			(stroke
				(width 0.1)
				(type default)
			)
			(layer "F.Fab")
		)
		(fp_line
			(start 0.67945 -0.3048)
			(end 0.67945 0.3048)
			(stroke
				(width 0.1)
				(type default)
			)
			(layer "F.Fab")
		)
		(fp_line
			(start -0.67945 -0.305054)
			(end -0.12065 -0.305054)
			(stroke
				(width 0.1)
				(type default)
			)
			(layer "F.Fab")
		)
		(fp_line
			(start -0.12065 -0.305054)
			(end -0.12065 -0.2794)
			(stroke
				(width 0.1)
				(type default)
			)
			(layer "F.Fab")
		)
		(pad "1" smd circle
			(at -0.40005 0 270)
			(size 0 0)
			(layers "F.Cu" "F.Mask" "F.Paste")
			(net "PVDDCR_CPU0_P1_VCC5")
		)
		(pad "2" smd circle
			(at 0.40005 0 270)
			(size 0 0)
			(layers "F.Cu" "F.Mask" "F.Paste")
			(net "GND")
		)
	)
	(footprint ""
		(layer "F.Cu")
		(at 370.969032 -35.037522 -90)
		(property "Reference" "C1352"
			(at 0 0 270)
			(layer "F.SilkS")
			(hide yes)
			(effects
				(font
					(size 1.27 1.27)
				)
			)
		)
		(property "Value" ""
			(at 0 0 270)
			(layer "F.Fab")
			(effects
				(font
					(size 1.27 1.27)
				)
			)
		)
		(duplicate_pad_numbers_are_jumpers no)
		(fp_line
			(start -0.7874 0.4064)
			(end -0.7874 -0.4064)
			(stroke
				(width 0.1524)
				(type default)
			)
			(layer "F.SilkS")
		)
		(fp_line
			(start 0.7874 0.4064)
			(end -0.7874 0.4064)
			(stroke
				(width 0.1524)
				(type default)
			)
			(layer "F.SilkS")
		)
		(fp_line
			(start -0.7874 -0.4064)
			(end 0.7874 -0.4064)
			(stroke
				(width 0.1524)
				(type default)
			)
			(layer "F.SilkS")
		)
		(fp_line
			(start 0.7874 -0.4064)
			(end 0.7874 0.4064)
			(stroke
				(width 0.1524)
				(type default)
			)
			(layer "F.SilkS")
		)
		(fp_line
			(start -0.67945 0.3048)
			(end -0.67945 -0.305054)
			(stroke
				(width 0.1)
				(type default)
			)
			(layer "F.Fab")
		)
		(fp_line
			(start -0.12065 0.3048)
			(end -0.67945 0.3048)
			(stroke
				(width 0.1)
				(type default)
			)
			(layer "F.Fab")
		)
		(fp_line
			(start 0.120396 0.3048)
			(end 0.120396 0.2794)
			(stroke
				(width 0.1)
				(type default)
			)
			(layer "F.Fab")
		)
		(fp_line
			(start 0.67945 0.3048)
			(end 0.120396 0.3048)
			(stroke
				(width 0.1)
				(type default)
			)
			(layer "F.Fab")
		)
		(fp_line
			(start -0.12065 0.2794)
			(end -0.12065 0.3048)
			(stroke
				(width 0.1)
				(type default)
			)
			(layer "F.Fab")
		)
		(fp_line
			(start 0.120396 0.2794)
			(end -0.12065 0.2794)
			(stroke
				(width 0.1)
				(type default)
			)
			(layer "F.Fab")
		)
		(fp_line
			(start -0.12065 -0.2794)
			(end 0.12065 -0.2794)
			(stroke
				(width 0.1)
				(type default)
			)
			(layer "F.Fab")
		)
		(fp_line
			(start 0.12065 -0.2794)
			(end 0.12065 -0.3048)
			(stroke
				(width 0.1)
				(type default)
			)
			(layer "F.Fab")
		)
		(fp_line
			(start 0.12065 -0.3048)
			(end 0.67945 -0.3048)
			(stroke
				(width 0.1)
				(type default)
			)
			(layer "F.Fab")
		)
		(fp_line
			(start 0.67945 -0.3048)
			(end 0.67945 0.3048)
			(stroke
				(width 0.1)
				(type default)
			)
			(layer "F.Fab")
		)
		(fp_line
			(start -0.67945 -0.305054)
			(end -0.12065 -0.305054)
			(stroke
				(width 0.1)
				(type default)
			)
			(layer "F.Fab")
		)
		(fp_line
			(start -0.12065 -0.305054)
			(end -0.12065 -0.2794)
			(stroke
				(width 0.1)
				(type default)
			)
			(layer "F.Fab")
		)
		(pad "1" smd circle
			(at -0.40005 0 270)
			(size 0 0)
			(layers "F.Cu" "F.Mask" "F.Paste")
			(net "PVDD18_S5_P0")
		)
		(pad "2" smd circle
			(at 0.40005 0 270)
			(size 0 0)
			(layers "F.Cu" "F.Mask" "F.Paste")
			(net "GND")
		)
	)
)
